# BASEBOARD_FAB2 (Tioga Pass) — schematic netlist excerpt (pin names and nets, part order shuffled) for the footprints in the layout excerpt that follows; sources: Cadence DE-HDL packaged netlist, KiCad conversion of Wiwynn_Tioga_Pass_MB.brd

R8E9  RES  33.2 1% CHIP  pkg 0402  page 184 : A = SPI_PCH_CLK ; B = SPI_PCH_TPM_CLK_R
C4B14  CAPP  68UF 16V 20% TANT  pkg 3018  page 195 : A = P12V_STBY ; B = GND
R1F1  RES  4.75K 1% CHIP  pkg 0402  page 161 : A = P3V3_STBY ; B = FAN_TACH0

(kicad_pcb
	(version 20260206)
	(generator "pcbnew")
	(generator_version "10.0")
	(general
		(thickness 1.6)
		(legacy_teardrops no)
	)
	(paper "A4")
	(title_block
		(title "Wiwynn_Tioga_Pass_MB.brd")
		(comment 1 "Tioga Pass / footprints 163-165 of 4770")
	)
	(layers
		(0 "F.Cu" signal "TOP")
		(4 "In1.Cu" signal "L2GND")
		(6 "In2.Cu" signal "L3")
		(8 "In3.Cu" signal "L4GND")
		(10 "In4.Cu" signal "L5")
		(12 "In5.Cu" signal "L6GND")
		(14 "In6.Cu" signal "L7VCC")
		(16 "In7.Cu" signal "L8VCC")
		(18 "In8.Cu" signal "L9GND")
		(20 "In9.Cu" signal "L10")
		(22 "In10.Cu" signal "L11GND")
		(24 "In11.Cu" signal "L12")
		(26 "In12.Cu" signal "L13GND")
		(2 "B.Cu" signal "BOTTOM")
		(9 "F.Adhes" user "F.Adhesive")
		(11 "B.Adhes" user "B.Adhesive")
		(13 "F.Paste" user "Package Geometry/Pastemask Top")
		(15 "B.Paste" user "Package Geometry/Pastemask Bottom")
		(5 "F.SilkS" user "Ref Des/Silkscreen Top")
		(7 "B.SilkS" user "Ref Des/Silkscreen Bottom")
		(1 "F.Mask" user "Board Geometry/Soldermask Top")
		(3 "B.Mask" user "Board Geometry/Soldermask Bottom")
		(17 "Dwgs.User" user "User.Drawings")
		(19 "Cmts.User" user "User.Comments")
		(21 "Eco1.User" user "User.Eco1")
		(23 "Eco2.User" user "User.Eco2")
		(25 "Edge.Cuts" user "Board Geometry/Outline")
		(27 "Margin" user)
		(31 "F.CrtYd" user "Package Geometry/Place Bound Top")
		(29 "B.CrtYd" user "Package Geometry/Place Bound Bottom")
		(35 "F.Fab" user "Ref Des/Assembly Top")
		(33 "B.Fab" user "Ref Des/Assembly Bottom")
	)
	(footprint ""
		(layer "F.Cu")
		(at 25.654 -30.861 90)
		(property "Reference" "R1F1"
			(at 0 0 90)
			(layer "F.SilkS")
			(hide yes)
			(effects
				(font
					(size 1.27 1.27)
				)
			)
		)
		(property "Value" ""
			(at 0 0 90)
			(layer "F.Fab")
			(effects
				(font
					(size 1.27 1.27)
				)
			)
		)
		(duplicate_pad_numbers_are_jumpers no)
		(fp_rect
			(start 0.2794 0.9906)
			(end -0.2794 -0.1016)
			(stroke
				(width 0)
				(type default)
			)
			(fill no)
			(layer "F.CrtYd")
		)
		(fp_line
			(start 0.2794 -0.1016)
			(end -0.2794 -0.1016)
			(stroke
				(width 0.1)
				(type default)
			)
			(layer "F.Fab")
		)
		(fp_line
			(start -0.2794 -0.1016)
			(end -0.2794 0.9906)
			(stroke
				(width 0.1)
				(type default)
			)
			(layer "F.Fab")
		)
		(fp_line
			(start 0.2794 0.9906)
			(end 0.2794 -0.1016)
			(stroke
				(width 0.1)
				(type default)
			)
			(layer "F.Fab")
		)
		(fp_line
			(start -0.2794 0.9906)
			(end 0.2794 0.9906)
			(stroke
				(width 0.1)
				(type default)
			)
			(layer "F.Fab")
		)
		(pad "1" smd rect
			(at 0 0 90)
			(size 0.508 0.508)
			(layers "F.Cu" "F.Mask" "F.Paste")
			(net "P3V3_STBY")
		)
		(pad "2" smd rect
			(at 0 0.889 90)
			(size 0.508 0.508)
			(layers "F.Cu" "F.Mask" "F.Paste")
			(net "FAN_TACH0")
		)
		(zone
			(layer "F.Cu")
			(hatch none 0.5)
			(connect_pads
				(clearance 0)
			)
			(min_thickness 0.25)
			(keepout
				(tracks not_allowed)
				(vias allowed)
				(pads allowed)
				(copperpour not_allowed)
				(footprints allowed)
			)
			(placement
				(enabled no)
				(sheetname "")
			)
			(fill
				(thermal_gap 0.5)
				(thermal_bridge_width 0.5)
				(island_removal_mode 0)
			)
			(polygon
				(pts
					(xy 26.289 -31.115) (xy 25.908 -31.115) (xy 25.908 -30.607) (xy 26.289 -30.607)
				)
			)
		)
		(zone
			(layer "F.Cu")
			(hatch none 0.5)
			(connect_pads
				(clearance 0)
			)
			(min_thickness 0.25)
			(keepout
				(tracks allowed)
				(vias not_allowed)
				(pads allowed)
				(copperpour not_allowed)
				(footprints allowed)
			)
			(placement
				(enabled no)
				(sheetname "")
			)
			(fill
				(thermal_gap 0.5)
				(thermal_bridge_width 0.5)
				(island_removal_mode 0)
			)
			(polygon
				(pts
					(xy 26.289 -31.115) (xy 25.908 -31.115) (xy 25.908 -30.607) (xy 26.289 -30.607)
				)
			)
		)
	)
	(footprint ""
		(layer "F.Cu")
		(at 407.878026 -66.758566)
		(property "Reference" "R8E9"
			(at 0 0 0)
			(layer "F.SilkS")
			(hide yes)
			(effects
				(font
					(size 1.27 1.27)
				)
			)
		)
		(property "Value" ""
			(at 0 0 0)
			(layer "F.Fab")
			(effects
				(font
					(size 1.27 1.27)
				)
			)
		)
		(duplicate_pad_numbers_are_jumpers no)
		(fp_poly
			(pts
				(xy -0.2794 -0.1016) (xy 0.2794 -0.1016) (xy 0.2794 0.9906) (xy -0.2794 0.9906)
			)
			(stroke
				(width 0)
				(type default)
			)
			(fill no)
			(layer "F.CrtYd")
		)
		(pad "1" smd rect
			(at 0 0)
			(size 0.508 0.508)
			(layers "F.Cu" "F.Mask" "F.Paste")
			(net "SPI_PCH_CLK")
		)
		(pad "2" smd rect
			(at 0 0.889)
			(size 0.508 0.508)
			(layers "F.Cu" "F.Mask" "F.Paste")
			(net "SPI_PCH_TPM_CLK_R")
		)
		(zone
			(layer "F.Cu")
			(hatch none 0.5)
			(connect_pads
				(clearance 0)
			)
			(min_thickness 0.25)
			(keepout
				(tracks allowed)
				(vias not_allowed)
				(pads allowed)
				(copperpour not_allowed)
				(footprints allowed)
			)
			(placement
				(enabled no)
				(sheetname "")
			)
			(fill
				(thermal_gap 0.5)
				(thermal_bridge_width 0.5)
				(island_removal_mode 0)
			)
			(polygon
				(pts
					(xy 407.624026 -66.504566) (xy 408.132026 -66.504566) (xy 408.132026 -66.123566) (xy 407.624026 -66.123566)
				)
			)
		)
		(zone
			(layer "F.Cu")
			(hatch none 0.5)
			(connect_pads
				(clearance 0)
			)
			(min_thickness 0.25)
			(keepout
				(tracks not_allowed)
				(vias allowed)
				(pads allowed)
				(copperpour not_allowed)
				(footprints allowed)
			)
			(placement
				(enabled no)
				(sheetname "")
			)
			(fill
				(thermal_gap 0.5)
				(thermal_bridge_width 0.5)
				(island_removal_mode 0)
			)
			(polygon
				(pts
					(xy 407.624026 -66.123566) (xy 408.132026 -66.123566) (xy 408.132026 -66.504566) (xy 407.624026 -66.504566)
				)
			)
		)
	)
	(footprint ""
		(layer "F.Cu")
		(at 167.386 -120.0658 90)
		(property "Reference" "C4B14"
			(at 3.27533 5.1054 0)
			(unlocked yes)
			(layer "F.SilkS")
			(effects
				(font
					(size 0.7874 0.5842)
					(thickness 0.1524)
				)
			)
		)
		(property "Value" ""
			(at 0 0 90)
			(layer "F.Fab")
			(effects
				(font
					(size 1.27 1.27)
				)
			)
		)
		(duplicate_pad_numbers_are_jumpers no)
		(fp_line
			(start 2.504948 -1.616456)
			(end 2.504948 1.633728)
			(stroke
				(width 0.1524)
				(type default)
			)
			(layer "F.SilkS")
		)
		(fp_line
			(start 1.6002 -1.616456)
			(end 2.504948 -1.616456)
			(stroke
				(width 0.1524)
				(type default)
			)
			(layer "F.SilkS")
		)
		(fp_line
			(start -1.6002 -1.616456)
			(end -2.563114 -1.616456)
			(stroke
				(width 0.1524)
				(type default)
			)
			(layer "F.SilkS")
		)
		(fp_line
			(start -2.563114 -1.616456)
			(end -2.563114 1.633728)
			(stroke
				(width 0.1524)
				(type default)
			)
			(layer "F.SilkS")
		)
		(fp_line
			(start 2.504948 1.633728)
			(end 1.6002 1.633728)
			(stroke
				(width 0.1524)
				(type default)
			)
			(layer "F.SilkS")
		)
		(fp_line
			(start -2.563114 1.633728)
			(end -1.6002 1.633728)
			(stroke
				(width 0.1524)
				(type default)
			)
			(layer "F.SilkS")
		)
		(fp_line
			(start 2.286 7.366)
			(end 2.286 1.63195)
			(stroke
				(width 0.1524)
				(type default)
			)
			(layer "F.SilkS")
		)
		(fp_line
			(start 2.286 7.366)
			(end 1.600708 7.366)
			(stroke
				(width 0.1524)
				(type default)
			)
			(layer "F.SilkS")
		)
		(fp_line
			(start -2.286 7.366)
			(end -2.286 1.632712)
			(stroke
				(width 0.1524)
				(type default)
			)
			(layer "F.SilkS")
		)
		(fp_line
			(start -2.286 7.366)
			(end -1.60147 7.366)
			(stroke
				(width 0.1524)
				(type default)
			)
			(layer "F.SilkS")
		)
		(fp_rect
			(start -2.286 7.366)
			(end 2.286 -0.254)
			(stroke
				(width 0)
				(type default)
			)
			(fill no)
			(layer "F.CrtYd")
		)
		(fp_line
			(start 2.286 -0.254)
			(end 2.286 7.366)
			(stroke
				(width 0.1)
				(type default)
			)
			(layer "F.Fab")
		)
		(fp_line
			(start -2.286 -0.254)
			(end 2.286 -0.254)
			(stroke
				(width 0.1)
				(type default)
			)
			(layer "F.Fab")
		)
		(fp_line
			(start 2.286 7.366)
			(end -2.286 7.366)
			(stroke
				(width 0.1)
				(type default)
			)
			(layer "F.Fab")
		)
		(fp_line
			(start -2.286 7.366)
			(end -2.286 -0.254)
			(stroke
				(width 0.1)
				(type default)
			)
			(layer "F.Fab")
		)
		(pad "1" smd rect
			(at 0 0 90)
			(size 2.54 3.048)
			(layers "F.Cu" "F.Mask" "F.Paste")
			(net "P12V_STBY")
		)
		(pad "2" smd rect
			(at 0 7.112 90)
			(size 2.54 3.048)
			(layers "F.Cu" "F.Mask" "F.Paste")
			(net "GND")
		)
	)
)
